(kicad_pcb
	(version 20241229)
	(generator "pcbnew")
	(generator_version "9.0")
	(general
		(thickness 1.711)
		(legacy_teardrops no)
	)
	(paper "A4")
	(title_block
		(title "Antmicro Baseboard for Jetson AGX Thor")
		(date "2026-02-18")
		(rev "1.1.0")
		(company "Antmicro Ltd")
		(comment 1 "www.antmicro.com")
		(comment 9 "footprints 1104-1108 of 1170")
	)
	(layers
		(0 "F.Cu" signal)
		(4 "In1.Cu" signal)
		(6 "In2.Cu" signal)
		(8 "In3.Cu" signal)
		(10 "In4.Cu" jumper)
		(12 "In5.Cu" signal)
		(14 "In6.Cu" signal)
		(16 "In7.Cu" signal)
		(18 "In8.Cu" signal)
		(2 "B.Cu" signal)
		(9 "F.Adhes" user "F.Adhesive")
		(11 "B.Adhes" user "B.Adhesive")
		(13 "F.Paste" user)
		(15 "B.Paste" user)
		(5 "F.SilkS" user "F.Silkscreen")
		(7 "B.SilkS" user "B.Silkscreen")
		(1 "F.Mask" user)
		(3 "B.Mask" user)
		(17 "Dwgs.User" user "User.Drawings")
		(19 "Cmts.User" user "User.Comments")
		(21 "Eco1.User" user "User.Eco1")
		(23 "Eco2.User" user "User.Eco2")
		(25 "Edge.Cuts" user)
		(27 "Margin" user)
		(31 "F.CrtYd" user "F.Courtyard")
		(29 "B.CrtYd" user "B.Courtyard")
		(35 "F.Fab" user)
		(33 "B.Fab" user)
	)
	(footprint "antmicro-footprints:R_0402_1005Metric"
		(layer "B.Cu")
		(at 215.538 75.970532 -90)
		(descr "Resistor SMD 0402")
		(tags "resistor SMD 0402")
		(property "Reference" "R286"
			(at -1.570532 -1.462 90)
			(layer "B.SilkS")
			(effects
				(font
					(size 0.7 0.7)
					(thickness 0.15)
				)
				(justify left bottom mirror)
			)
		)
		(property "Value" "R_10M_0402"
			(at -1.011843 -1.772047 90)
			(layer "B.Fab")
			(effects
				(font
					(size 0.7 0.7)
					(thickness 0.15)
				)
				(justify left bottom mirror)
			)
		)
		(property "Datasheet" "https://www.bourns.com/docs/product-datasheets/cr.pdf"
			(at 0 0 90)
			(layer "B.Fab")
			(hide yes)
			(effects
				(font
					(size 1.27 1.27)
					(thickness 0.15)
				)
				(justify mirror)
			)
		)
		(property "Description" "SMD Chip Resistor"
			(at 0 0 90)
			(layer "B.Fab")
			(hide yes)
			(effects
				(font
					(size 1.27 1.27)
					(thickness 0.15)
				)
				(justify mirror)
			)
		)
		(property "MPN" "CR0402-FX-1005GLF"
			(at 0 0 90)
			(unlocked yes)
			(layer "B.Fab")
			(hide yes)
			(effects
				(font
					(size 1 1)
					(thickness 0.15)
				)
				(justify mirror)
			)
		)
		(property "Manufacturer" "Bourns"
			(at 0 0 90)
			(unlocked yes)
			(layer "B.Fab")
			(hide yes)
			(effects
				(font
					(size 1 1)
					(thickness 0.15)
				)
				(justify mirror)
			)
		)
		(property "License" "Apache-2.0"
			(at 0 0 90)
			(unlocked yes)
			(layer "B.Fab")
			(hide yes)
			(effects
				(font
					(size 1 1)
					(thickness 0.15)
				)
				(justify mirror)
			)
		)
		(property "Author" "Antmicro"
			(at 0 0 90)
			(unlocked yes)
			(layer "B.Fab")
			(hide yes)
			(effects
				(font
					(size 1 1)
					(thickness 0.15)
				)
				(justify mirror)
			)
		)
		(property "Val" "10M"
			(at 0 0 90)
			(unlocked yes)
			(layer "B.Fab")
			(hide yes)
			(effects
				(font
					(size 1 1)
					(thickness 0.15)
				)
				(justify mirror)
			)
		)
		(property "Tolerance" "1%"
			(at 0 0 90)
			(unlocked yes)
			(layer "B.Fab")
			(hide yes)
			(effects
				(font
					(size 1 1)
					(thickness 0.15)
				)
				(justify mirror)
			)
		)
		(sheetname "/USB Debug, PD/")
		(sheetfile "usb_debug_pd.kicad_sch")
		(attr smd exclude_from_pos_files exclude_from_bom dnp)
		(fp_rect
			(start -0.925 0.47)
			(end 0.925 -0.47)
			(stroke
				(width 0.05)
				(type default)
			)
			(fill no)
			(layer "B.CrtYd")
		)
		(fp_rect
			(start -0.5 0.25)
			(end 0.5 -0.25)
			(stroke
				(width 0.15)
				(type solid)
			)
			(fill no)
			(layer "B.Fab")
		)
		(fp_text user "${REFERENCE}"
			(at -0.95 -3.168 90)
			(layer "B.Fab")
			(effects
				(font
					(size 0.7 0.7)
					(thickness 0.15)
				)
				(justify left bottom mirror)
			)
		)
		(fp_text user "Author: Antmicro"
			(at -0.95 -4.169 90)
			(layer "B.Fab")
			(effects
				(font
					(size 0.7 0.7)
					(thickness 0.15)
				)
				(justify left bottom mirror)
			)
		)
		(fp_text user "License: Apache-2.0"
			(at -0.95 -5.169 90)
			(layer "B.Fab")
			(effects
				(font
					(size 0.7 0.7)
					(thickness 0.15)
				)
				(justify left bottom mirror)
			)
		)
		(pad "1" smd roundrect
			(at -0.48 0 270)
			(size 0.59 0.64)
			(layers "B.Cu" "B.Mask" "B.Paste")
			(roundrect_rratio 0.25)
			(net 1 "GND")
			(pintype "passive")
		)
		(pad "2" smd roundrect
			(at 0.48 0 270)
			(size 0.59 0.64)
			(layers "B.Cu" "B.Mask" "B.Paste")
			(roundrect_rratio 0.25)
			(net 104 "/M.2/~{PEWAKE}")
			(pintype "passive")
		)
	)
	(footprint "antmicro-footprints:TP_SMD_0.75mm"
		(layer "B.Cu")
		(at 87.8 67.6 -90)
		(property "Reference" "TP104"
			(at 0.6 -0.4 90)
			(layer "B.SilkS")
			(effects
				(font
					(size 0.7 0.7)
					(thickness 0.15)
				)
				(justify left bottom mirror)
			)
		)
		(property "Value" "TP_0.75mm_SMD"
			(at 0 -1.2 90)
			(layer "B.Fab")
			(effects
				(font
					(size 0.7 0.7)
					(thickness 0.15)
				)
				(justify left bottom mirror)
			)
		)
		(property "Description" "SMT test point"
			(at 0 0 90)
			(layer "B.Fab")
			(hide yes)
			(effects
				(font
					(size 1.27 1.27)
					(thickness 0.15)
				)
				(justify mirror)
			)
		)
		(property "MPN" ""
			(at 0 0 90)
			(unlocked yes)
			(layer "B.Fab")
			(hide yes)
			(effects
				(font
					(size 1 1)
					(thickness 0.15)
				)
				(justify mirror)
			)
		)
		(property "Manufacturer" ""
			(at 0 0 90)
			(unlocked yes)
			(layer "B.Fab")
			(hide yes)
			(effects
				(font
					(size 1 1)
					(thickness 0.15)
				)
				(justify mirror)
			)
		)
		(property "Author" "Antmicro"
			(at 0 0 90)
			(unlocked yes)
			(layer "B.Fab")
			(hide yes)
			(effects
				(font
					(size 1 1)
					(thickness 0.15)
				)
				(justify mirror)
			)
		)
		(property "License" "Apache-2.0"
			(at 0 0 90)
			(unlocked yes)
			(layer "B.Fab")
			(hide yes)
			(effects
				(font
					(size 1 1)
					(thickness 0.15)
				)
				(justify mirror)
			)
		)
		(sheetname "/SoM_IO/")
		(sheetfile "som_io.kicad_sch")
		(attr exclude_from_pos_files exclude_from_bom)
		(fp_circle
			(center 0 0)
			(end 0.475 0)
			(stroke
				(width 0.05)
				(type default)
			)
			(fill no)
			(layer "B.CrtYd")
		)
		(fp_text user "${REFERENCE}"
			(at -0.4 -2.7 90)
			(layer "B.Fab")
			(effects
				(font
					(size 0.7 0.7)
					(thickness 0.15)
				)
				(justify left bottom mirror)
			)
		)
		(fp_text user "License: Apache-2.0"
			(at -0.4 -5.101 90)
			(layer "B.Fab")
			(effects
				(font
					(size 0.7 0.7)
					(thickness 0.15)
				)
				(justify left bottom mirror)
			)
		)
		(fp_text user "Author: Antmicro"
			(at -0.4 -3.901 90)
			(layer "B.Fab")
			(effects
				(font
					(size 0.7 0.7)
					(thickness 0.15)
				)
				(justify left bottom mirror)
			)
		)
		(pad "1" smd circle
			(at 0 0 270)
			(size 0.75 0.75)
			(layers "B.Cu" "B.Mask")
			(net 96 "/SoM_IO/I2C1_SDA_1V8")
			(pinfunction "1")
			(pintype "passive")
		)
	)
	(footprint "antmicro-footprints:C_0402_1005Metric"
		(layer "B.Cu")
		(at 218.62 59.98 180)
		(descr "Capacitor SMD 0402")
		(tags "capacitor SMD 0402")
		(property "Reference" "C161"
			(at 3.72 0.31 0)
			(layer "B.SilkS")
			(effects
				(font
					(size 0.7 0.7)
					(thickness 0.15)
				)
				(justify right top mirror)
			)
		)
		(property "Value" "C_1u_0402"
			(at -1.022927 -2.155213 0)
			(layer "B.Fab")
			(effects
				(font
					(size 0.7 0.7)
					(thickness 0.15)
				)
				(justify left bottom mirror)
			)
		)
		(property "Datasheet" "https://product.tdk.com/en/search/capacitor/ceramic/mlcc/info?part_no=C1005X6S1A105K050BC"
			(at 0 0 0)
			(layer "B.Fab")
			(hide yes)
			(effects
				(font
					(size 1.27 1.27)
					(thickness 0.15)
				)
				(justify mirror)
			)
		)
		(property "Description" "SMD Multilayer Ceramic Capacitor, 1 µF, 10 V, 0402 [1005 Metric], ± 10%, X6S, C"
			(at 0 0 0)
			(layer "B.Fab")
			(hide yes)
			(effects
				(font
					(size 1.27 1.27)
					(thickness 0.15)
				)
				(justify mirror)
			)
		)
		(property "Manufacturer" "TDK"
			(at 0 0 0)
			(unlocked yes)
			(layer "B.Fab")
			(hide yes)
			(effects
				(font
					(size 1 1)
					(thickness 0.15)
				)
				(justify mirror)
			)
		)
		(property "MPN" "C1005X6S1A105K050BC"
			(at 0 0 0)
			(unlocked yes)
			(layer "B.Fab")
			(hide yes)
			(effects
				(font
					(size 1 1)
					(thickness 0.15)
				)
				(justify mirror)
			)
		)
		(property "Val" "1u"
			(at 0 0 0)
			(unlocked yes)
			(layer "B.Fab")
			(hide yes)
			(effects
				(font
					(size 1 1)
					(thickness 0.15)
				)
				(justify mirror)
			)
		)
		(property "License" "Apache-2.0"
			(at 0 0 0)
			(unlocked yes)
			(layer "B.Fab")
			(hide yes)
			(effects
				(font
					(size 1 1)
					(thickness 0.15)
				)
				(justify mirror)
			)
		)
		(property "Author" "Antmicro"
			(at 0 0 0)
			(unlocked yes)
			(layer "B.Fab")
			(hide yes)
			(effects
				(font
					(size 1 1)
					(thickness 0.15)
				)
				(justify mirror)
			)
		)
		(property "Voltage" ""
			(at 0 0 0)
			(unlocked yes)
			(layer "B.Fab")
			(hide yes)
			(effects
				(font
					(size 1 1)
					(thickness 0.15)
				)
				(justify mirror)
			)
		)
		(property "Dielectric" ""
			(at 0 0 0)
			(unlocked yes)
			(layer "B.Fab")
			(hide yes)
			(effects
				(font
					(size 1 1)
					(thickness 0.15)
				)
				(justify mirror)
			)
		)
		(sheetname "/CSI/")
		(sheetfile "csi.kicad_sch")
		(attr smd)
		(fp_rect
			(start -0.925 0.47)
			(end 0.925 -0.47)
			(stroke
				(width 0.05)
				(type default)
			)
			(fill no)
			(layer "B.CrtYd")
		)
		(fp_line
			(start 0.504 0.25)
			(end 0.504 -0.248)
			(stroke
				(width 0.15)
				(type solid)
			)
			(layer "B.Fab")
		)
		(fp_line
			(start 0.504 -0.248)
			(end -0.494 -0.248)
			(stroke
				(width 0.15)
				(type solid)
			)
			(layer "B.Fab")
		)
		(fp_line
			(start -0.494 0.25)
			(end 0.504 0.25)
			(stroke
				(width 0.15)
				(type solid)
			)
			(layer "B.Fab")
		)
		(fp_line
			(start -0.494 -0.248)
			(end -0.494 0.25)
			(stroke
				(width 0.15)
				(type solid)
			)
			(layer "B.Fab")
		)
		(fp_text user "${REFERENCE}"
			(at -0.939 -4.599 0)
			(layer "B.Fab")
			(effects
				(font
					(size 0.7 0.7)
					(thickness 0.15)
				)
				(justify left bottom mirror)
			)
		)
		(fp_text user "Author: Antmicro"
			(at -0.939 -3.399 0)
			(layer "B.Fab")
			(effects
				(font
					(size 0.7 0.7)
					(thickness 0.15)
				)
				(justify left bottom mirror)
			)
		)
		(fp_text user "License: Apache-2.0"
			(at -0.939 -5.799 0)
			(layer "B.Fab")
			(effects
				(font
					(size 0.7 0.7)
					(thickness 0.15)
				)
				(justify left bottom mirror)
			)
		)
		(pad "1" smd roundrect
			(at -0.48 0 180)
			(size 0.59 0.64)
			(layers "B.Cu" "B.Mask" "B.Paste")
			(roundrect_rratio 0.25)
			(net 1 "GND")
			(pintype "passive")
		)
		(pad "2" smd roundrect
			(at 0.48 0 180)
			(size 0.59 0.64)
			(layers "B.Cu" "B.Mask" "B.Paste")
			(roundrect_rratio 0.25)
			(net 9 "/CSI/CSIB_5V")
			(pintype "passive")
		)
	)
	(footprint "antmicro-footprints:R_0402_1005Metric"
		(layer "B.Cu")
		(at 63.97 63.58 90)
		(descr "Resistor SMD 0402")
		(tags "resistor SMD 0402")
		(property "Reference" "R158"
			(at 0.78 -0.4 90)
			(layer "B.SilkS")
			(effects
				(font
					(size 0.7 0.7)
					(thickness 0.15)
				)
				(justify right top mirror)
			)
		)
		(property "Value" "R_0R_0402"
			(at -1.011843 -1.772046 90)
			(layer "B.Fab")
			(effects
				(font
					(size 0.7 0.7)
					(thickness 0.15)
				)
				(justify right top mirror)
			)
		)
		(property "Datasheet" "https://industrial.panasonic.com/cdbs/www-data/pdf/RDA0000/AOA0000C301.pdf"
			(at 0 0 90)
			(layer "B.Fab")
			(hide yes)
			(effects
				(font
					(size 1.27 1.27)
					(thickness 0.15)
				)
				(justify mirror)
			)
		)
		(property "Description" "SMD Chip Resistor, Jumper, 0 ohm, 100 mW, 0402 [1005 Metric], Thick Film, General Purpose"
			(at 0 0 90)
			(layer "B.Fab")
			(hide yes)
			(effects
				(font
					(size 1.27 1.27)
					(thickness 0.15)
				)
				(justify mirror)
			)
		)
		(property "Manufacturer" "Panasonic"
			(at 0 0 270)
			(unlocked yes)
			(layer "B.Fab")
			(hide yes)
			(effects
				(font
					(size 1 1)
					(thickness 0.15)
				)
				(justify mirror)
			)
		)
		(property "MPN" "ERJ2GE0R00X"
			(at 0 0 270)
			(unlocked yes)
			(layer "B.Fab")
			(hide yes)
			(effects
				(font
					(size 1 1)
					(thickness 0.15)
				)
				(justify mirror)
			)
		)
		(property "Val" "0R"
			(at 0 0 270)
			(unlocked yes)
			(layer "B.Fab")
			(hide yes)
			(effects
				(font
					(size 1 1)
					(thickness 0.15)
				)
				(justify mirror)
			)
		)
		(property "License" "Apache-2.0"
			(at 0 0 270)
			(unlocked yes)
			(layer "B.Fab")
			(hide yes)
			(effects
				(font
					(size 1 1)
					(thickness 0.15)
				)
				(justify mirror)
			)
		)
		(property "Author" "Antmicro"
			(at 0 0 270)
			(unlocked yes)
			(layer "B.Fab")
			(hide yes)
			(effects
				(font
					(size 1 1)
					(thickness 0.15)
				)
				(justify mirror)
			)
		)
		(property "Tolerance" "~"
			(at 0 0 270)
			(unlocked yes)
			(layer "B.Fab")
			(hide yes)
			(effects
				(font
					(size 1 1)
					(thickness 0.15)
				)
				(justify mirror)
			)
		)
		(property "Current" "1A"
			(at 0 0 270)
			(unlocked yes)
			(layer "B.Fab")
			(hide yes)
			(effects
				(font
					(size 1 1)
					(thickness 0.15)
				)
				(justify mirror)
			)
		)
		(sheetname "/CSI/")
		(sheetfile "csi.kicad_sch")
		(attr smd)
		(fp_poly
			(pts
				(xy -0.925 0.47) (xy -0.925 -0.47) (xy 0.925 -0.47) (xy 0.925 0.47)
			)
			(stroke
				(width 0.05)
				(type default)
			)
			(fill no)
			(layer "B.CrtYd")
		)
		(fp_poly
			(pts
				(xy -0.5 0.25) (xy -0.5 -0.25) (xy 0.5 -0.25) (xy 0.5 0.25)
			)
			(stroke
				(width 0.15)
				(type solid)
			)
			(fill no)
			(layer "B.Fab")
		)
		(fp_text user "Author: Antmicro"
			(at -0.95 -4.169 90)
			(layer "B.Fab")
			(effects
				(font
					(size 0.7 0.7)
					(thickness 0.15)
				)
				(justify right top mirror)
			)
		)
		(fp_text user "License: Apache-2.0"
			(at -0.949999 -5.169 90)
			(layer "B.Fab")
			(effects
				(font
					(size 0.7 0.7)
					(thickness 0.15)
				)
				(justify right top mirror)
			)
		)
		(fp_text user "${REFERENCE}"
			(at -0.95 -3.168 90)
			(layer "B.Fab")
			(effects
				(font
					(size 0.7 0.7)
					(thickness 0.15)
				)
				(justify right top mirror)
			)
		)
		(pad "1" smd roundrect
			(at -0.48 0 90)
			(size 0.59 0.64)
			(layers "B.Cu" "B.Mask" "B.Paste")
			(roundrect_rratio 0.25)
			(net 979 "/CSI/CSIA_I2C_VCC")
			(pintype "passive")
		)
		(pad "2" smd roundrect
			(at 0.48 0 90)
			(size 0.59 0.64)
			(layers "B.Cu" "B.Mask" "B.Paste")
			(roundrect_rratio 0.25)
			(net 2 "+3V3")
			(pintype "passive")
		)
	)
	(footprint "antmicro-footprints:R_0402_1005Metric"
		(layer "B.Cu")
		(at 157.15 66.51 180)
		(descr "Resistor SMD 0402")
		(tags "resistor SMD 0402")
		(property "Reference" "R293"
			(at -1.05 -4.22 0)
			(layer "B.SilkS")
			(effects
				(font
					(size 0.7 0.7)
					(thickness 0.15)
				)
				(justify left bottom mirror)
			)
		)
		(property "Value" "R_0R_0402"
			(at -1.011843 -1.772047 0)
			(layer "B.Fab")
			(effects
				(font
					(size 0.7 0.7)
					(thickness 0.15)
				)
				(justify left bottom mirror)
			)
		)
		(property "Datasheet" "https://industrial.panasonic.com/cdbs/www-data/pdf/RDA0000/AOA0000C301.pdf"
			(at 0 0 0)
			(layer "B.Fab")
			(hide yes)
			(effects
				(font
					(size 1.27 1.27)
					(thickness 0.15)
				)
				(justify mirror)
			)
		)
		(property "Description" "SMD Chip Resistor, Jumper, 0 ohm, 100 mW, 0402 [1005 Metric], Thick Film, General Purpose"
			(at 0 0 0)
			(layer "B.Fab")
			(hide yes)
			(effects
				(font
					(size 1.27 1.27)
					(thickness 0.15)
				)
				(justify mirror)
			)
		)
		(property "MPN" "ERJ2GE0R00X"
			(at 0 0 0)
			(unlocked yes)
			(layer "B.Fab")
			(hide yes)
			(effects
				(font
					(size 1 1)
					(thickness 0.15)
				)
				(justify mirror)
			)
		)
		(property "Manufacturer" "Panasonic"
			(at 0 0 0)
			(unlocked yes)
			(layer "B.Fab")
			(hide yes)
			(effects
				(font
					(size 1 1)
					(thickness 0.15)
				)
				(justify mirror)
			)
		)
		(property "License" "Apache-2.0"
			(at 0 0 0)
			(unlocked yes)
			(layer "B.Fab")
			(hide yes)
			(effects
				(font
					(size 1 1)
					(thickness 0.15)
				)
				(justify mirror)
			)
		)
		(property "Author" "Antmicro"
			(at 0 0 0)
			(unlocked yes)
			(layer "B.Fab")
			(hide yes)
			(effects
				(font
					(size 1 1)
					(thickness 0.15)
				)
				(justify mirror)
			)
		)
		(property "Val" "0R"
			(at 0 0 0)
			(unlocked yes)
			(layer "B.Fab")
			(hide yes)
			(effects
				(font
					(size 1 1)
					(thickness 0.15)
				)
				(justify mirror)
			)
		)
		(property "Tolerance" "~"
			(at 0 0 0)
			(unlocked yes)
			(layer "B.Fab")
			(hide yes)
			(effects
				(font
					(size 1 1)
					(thickness 0.15)
				)
				(justify mirror)
			)
		)
		(property "Current" "1A"
			(at 0 0 0)
			(unlocked yes)
			(layer "B.Fab")
			(hide yes)
			(effects
				(font
					(size 1 1)
					(thickness 0.15)
				)
				(justify mirror)
			)
		)
		(sheetname "/SoM_IO2/")
		(sheetfile "som_io2.kicad_sch")
		(attr smd exclude_from_pos_files exclude_from_bom dnp)
		(fp_rect
			(start -0.925 0.47)
			(end 0.925 -0.47)
			(stroke
				(width 0.05)
				(type default)
			)
			(fill no)
			(layer "B.CrtYd")
		)
		(fp_rect
			(start -0.5 0.25)
			(end 0.5 -0.25)
			(stroke
				(width 0.15)
				(type solid)
			)
			(fill no)
			(layer "B.Fab")
		)
		(fp_text user "${REFERENCE}"
			(at -0.95 -3.168 0)
			(layer "B.Fab")
			(effects
				(font
					(size 0.7 0.7)
					(thickness 0.15)
				)
				(justify left bottom mirror)
			)
		)
		(fp_text user "License: Apache-2.0"
			(at -0.95 -5.169 0)
			(layer "B.Fab")
			(effects
				(font
					(size 0.7 0.7)
					(thickness 0.15)
				)
				(justify left bottom mirror)
			)
		)
		(fp_text user "Author: Antmicro"
			(at -0.95 -4.169 0)
			(layer "B.Fab")
			(effects
				(font
					(size 0.7 0.7)
					(thickness 0.15)
				)
				(justify left bottom mirror)
			)
		)
		(pad "1" smd roundrect
			(at -0.48 0 180)
			(size 0.59 0.64)
			(layers "B.Cu" "B.Mask" "B.Paste")
			(roundrect_rratio 0.25)
			(net 1029 "Net-(U59-B2Y)")
			(pintype "passive")
		)
		(pad "2" smd roundrect
			(at 0.48 0 180)
			(size 0.59 0.64)
			(layers "B.Cu" "B.Mask" "B.Paste")
			(roundrect_rratio 0.25)
			(net 715 "/SoM_IO2/JTAG_TDI")
			(pintype "passive")
		)
	)
)
